(kicad_pcb
	(version 20260206)
	(generator "pcbnew")
	(generator_version "10.0")
	(general
		(thickness 1.6)
		(legacy_teardrops no)
	)
	(paper "A4")
	(title_block
		(title "timecard-production-celestica-r4006 — R4006-B0001-02_R01.brd")
		(comment 1 "Time Appliance Project (Time Card) / footprints 517-521 of 1113")
	)
	(layers
		(0 "F.Cu" signal "TOP")
		(4 "In1.Cu" signal "L02_GND1")
		(6 "In2.Cu" signal "L03_SIG1")
		(8 "In3.Cu" signal "L04_GND2")
		(10 "In4.Cu" signal "L05_VCC1")
		(12 "In5.Cu" signal "L06_VCC2")
		(14 "In6.Cu" signal "L07_GND3")
		(16 "In7.Cu" signal "L08_SIG2")
		(18 "In8.Cu" signal "L09_GND4")
		(2 "B.Cu" signal "BOTTOM")
		(9 "F.Adhes" user "F.Adhesive")
		(11 "B.Adhes" user "B.Adhesive")
		(13 "F.Paste" user "Package Geometry/Pastemask Top")
		(15 "B.Paste" user "Package Geometry/Pastemask Bottom")
		(5 "F.SilkS" user "Ref Des/Silkscreen Top")
		(7 "B.SilkS" user "Ref Des/Silkscreen Bottom")
		(1 "F.Mask" user "Board Geometry/Soldermask Top")
		(3 "B.Mask" user "Board Geometry/Soldermask Bottom")
		(17 "Dwgs.User" user "User.Drawings")
		(19 "Cmts.User" user "User.Comments")
		(21 "Eco1.User" user "User.Eco1")
		(23 "Eco2.User" user "User.Eco2")
		(25 "Edge.Cuts" user "Board Geometry/Outline")
		(27 "Margin" user)
		(31 "F.CrtYd" user "Package Geometry/Place Bound Top")
		(29 "B.CrtYd" user "Package Geometry/Place Bound Bottom")
		(35 "F.Fab" user "Ref Des/Assembly Top")
		(33 "B.Fab" user "Ref Des/Assembly Bottom")
	)
	(footprint ""
		(layer "F.Cu")
		(at 14.6812 -65.786 -90)
		(property "Reference" "R361"
			(at -5.334 0.41783 90)
			(unlocked yes)
			(layer "F.SilkS")
			(effects
				(font
					(size 0.7874 0.5842)
					(thickness 0.1524)
				)
			)
		)
		(property "Value" "VAL*"
			(at 0.02032 2.13233 270)
			(unlocked yes)
			(layer "F.Fab")
			(hide yes)
			(effects
				(font
					(size 0.7874 0.5842)
					(thickness 0.1524)
				)
			)
		)
		(property "Device Type" "RESISTOR-G155-14701-01,4.7KOHMA"
			(at 0.008382 1.210564 270)
			(unlocked yes)
			(layer "F.Fab")
			(hide yes)
			(effects
				(font
					(size 0.7874 0.5842)
					(thickness 0.1524)
				)
			)
		)
		(property "User Part Number" "PARTNUM*"
			(at 0.02032 4.024884 270)
			(unlocked yes)
			(layer "Cmts.User")
			(hide yes)
			(effects
				(font
					(size 0.7874 0.5842)
					(thickness 0.1524)
				)
			)
		)
		(property "Tolerance" "TOL*"
			(at 0.044704 3.05435 270)
			(unlocked yes)
			(layer "Cmts.User")
			(hide yes)
			(effects
				(font
					(size 0.7874 0.5842)
					(thickness 0.1524)
				)
			)
		)
		(duplicate_pad_numbers_are_jumpers no)
		(fp_line
			(start -1.143 0.5588)
			(end 1.143 0.5588)
			(stroke
				(width 0.1)
				(type default)
			)
			(layer "F.SilkS")
		)
		(fp_line
			(start 1.143 0.5588)
			(end 1.143 -0.5588)
			(stroke
				(width 0.1)
				(type default)
			)
			(layer "F.SilkS")
		)
		(fp_line
			(start -1.143 -0.5588)
			(end -1.143 0.5588)
			(stroke
				(width 0.1)
				(type default)
			)
			(layer "F.SilkS")
		)
		(fp_line
			(start 1.143 -0.5588)
			(end -1.143 -0.5588)
			(stroke
				(width 0.1)
				(type default)
			)
			(layer "F.SilkS")
		)
		(fp_rect
			(start -1.143 -0.5588)
			(end 1.143 0.5588)
			(stroke
				(width 0)
				(type default)
			)
			(fill no)
			(layer "F.CrtYd")
		)
		(fp_line
			(start -0.508 0.3048)
			(end 0.508 0.3048)
			(stroke
				(width 0.1)
				(type default)
			)
			(layer "F.Fab")
		)
		(fp_line
			(start 0.508 0.3048)
			(end 0.508 -0.3048)
			(stroke
				(width 0.1)
				(type default)
			)
			(layer "F.Fab")
		)
		(fp_line
			(start -0.508 -0.3048)
			(end -0.508 0.3048)
			(stroke
				(width 0.1)
				(type default)
			)
			(layer "F.Fab")
		)
		(fp_line
			(start 0.508 -0.3048)
			(end -0.508 -0.3048)
			(stroke
				(width 0.1)
				(type default)
			)
			(layer "F.Fab")
		)
		(pad "1" smd rect
			(at -0.5334 0 270)
			(size 0.7112 0.6096)
			(layers "F.Cu" "F.Mask" "F.Paste")
			(net "XP3R3V_FPGA")
		)
		(pad "2" smd rect
			(at 0.5334 0 270)
			(size 0.7112 0.6096)
			(layers "F.Cu" "F.Mask" "F.Paste")
			(net "SMA1_SIG_OUT_BF_EN_N")
		)
		(zone
			(layer "F.Cu")
			(hatch none 0.5)
			(connect_pads
				(clearance 0)
			)
			(min_thickness 0.25)
			(keepout
				(tracks not_allowed)
				(vias allowed)
				(pads allowed)
				(copperpour not_allowed)
				(footprints allowed)
			)
			(placement
				(enabled no)
				(sheetname "")
			)
			(fill
				(thermal_gap 0.5)
				(thermal_bridge_width 0.5)
				(island_removal_mode 0)
			)
			(polygon
				(pts
					(xy 14.986 -65.8622) (xy 14.3764 -65.8622) (xy 14.3764 -65.7098) (xy 14.986 -65.7098)
				)
			)
		)
		(zone
			(layer "F.Cu")
			(hatch none 0.5)
			(connect_pads
				(clearance 0)
			)
			(min_thickness 0.25)
			(keepout
				(tracks allowed)
				(vias not_allowed)
				(pads allowed)
				(copperpour not_allowed)
				(footprints allowed)
			)
			(placement
				(enabled no)
				(sheetname "")
			)
			(fill
				(thermal_gap 0.5)
				(thermal_bridge_width 0.5)
				(island_removal_mode 0)
			)
			(polygon
				(pts
					(xy 14.986 -65.8622) (xy 14.3764 -65.8622) (xy 14.3764 -65.7098) (xy 14.986 -65.7098)
				)
			)
		)
	)
	(footprint ""
		(layer "F.Cu")
		(at 7.112 -81.534 90)
		(property "Reference" "R427"
			(at -2.667 -0.34163 90)
			(unlocked yes)
			(layer "F.SilkS")
			(effects
				(font
					(size 0.7874 0.5842)
					(thickness 0.1524)
				)
			)
		)
		(property "Value" "VAL*"
			(at 0.02032 2.13233 90)
			(unlocked yes)
			(layer "F.Fab")
			(hide yes)
			(effects
				(font
					(size 0.7874 0.5842)
					(thickness 0.1524)
				)
			)
		)
		(property "Device Type" "RESISTOR-G155-11000-01,100OHM,A"
			(at 0.008382 1.210564 90)
			(unlocked yes)
			(layer "F.Fab")
			(hide yes)
			(effects
				(font
					(size 0.7874 0.5842)
					(thickness 0.1524)
				)
			)
		)
		(property "User Part Number" "PARTNUM*"
			(at 0.02032 4.024884 90)
			(unlocked yes)
			(layer "Cmts.User")
			(hide yes)
			(effects
				(font
					(size 0.7874 0.5842)
					(thickness 0.1524)
				)
			)
		)
		(property "Tolerance" "TOL*"
			(at 0.044704 3.05435 90)
			(unlocked yes)
			(layer "Cmts.User")
			(hide yes)
			(effects
				(font
					(size 0.7874 0.5842)
					(thickness 0.1524)
				)
			)
		)
		(duplicate_pad_numbers_are_jumpers no)
		(fp_line
			(start 1.143 -0.5588)
			(end -1.143 -0.5588)
			(stroke
				(width 0.1)
				(type default)
			)
			(layer "F.SilkS")
		)
		(fp_line
			(start -1.143 -0.5588)
			(end -1.143 0.5588)
			(stroke
				(width 0.1)
				(type default)
			)
			(layer "F.SilkS")
		)
		(fp_line
			(start 1.143 0.5588)
			(end 1.143 -0.5588)
			(stroke
				(width 0.1)
				(type default)
			)
			(layer "F.SilkS")
		)
		(fp_line
			(start -1.143 0.5588)
			(end 1.143 0.5588)
			(stroke
				(width 0.1)
				(type default)
			)
			(layer "F.SilkS")
		)
		(fp_poly
			(pts
				(xy -1.143 0.5588) (xy 1.143 0.5588) (xy 1.143 -0.5588) (xy -1.143 -0.5588)
			)
			(stroke
				(width 0)
				(type default)
			)
			(fill no)
			(layer "F.CrtYd")
		)
		(fp_line
			(start 0.508 -0.3048)
			(end -0.508 -0.3048)
			(stroke
				(width 0.1)
				(type default)
			)
			(layer "F.Fab")
		)
		(fp_line
			(start -0.508 -0.3048)
			(end -0.508 0.3048)
			(stroke
				(width 0.1)
				(type default)
			)
			(layer "F.Fab")
		)
		(fp_line
			(start 0.508 0.3048)
			(end 0.508 -0.3048)
			(stroke
				(width 0.1)
				(type default)
			)
			(layer "F.Fab")
		)
		(fp_line
			(start -0.508 0.3048)
			(end 0.508 0.3048)
			(stroke
				(width 0.1)
				(type default)
			)
			(layer "F.Fab")
		)
		(pad "1" smd rect
			(at -0.5334 0 90)
			(size 0.7112 0.6096)
			(layers "F.Cu" "F.Mask" "F.Paste")
			(net "FPGA_OUT_GPS_LED_RED_N")
		)
		(pad "2" smd rect
			(at 0.5334 0 90)
			(size 0.7112 0.6096)
			(layers "F.Cu" "F.Mask" "F.Paste")
			(net "UNNAMED_14_LED4PV14_I269_3")
		)
		(zone
			(layer "F.Cu")
			(hatch none 0.5)
			(connect_pads
				(clearance 0)
			)
			(min_thickness 0.25)
			(keepout
				(tracks not_allowed)
				(vias allowed)
				(pads allowed)
				(copperpour not_allowed)
				(footprints allowed)
			)
			(placement
				(enabled no)
				(sheetname "")
			)
			(fill
				(thermal_gap 0.5)
				(thermal_bridge_width 0.5)
				(island_removal_mode 0)
			)
			(polygon
				(pts
					(xy 7.4168 -81.4578) (xy 7.4168 -81.6102) (xy 6.8072 -81.6102) (xy 6.8072 -81.4578)
				)
			)
		)
		(zone
			(layer "F.Cu")
			(hatch none 0.5)
			(connect_pads
				(clearance 0)
			)
			(min_thickness 0.25)
			(keepout
				(tracks allowed)
				(vias not_allowed)
				(pads allowed)
				(copperpour not_allowed)
				(footprints allowed)
			)
			(placement
				(enabled no)
				(sheetname "")
			)
			(fill
				(thermal_gap 0.5)
				(thermal_bridge_width 0.5)
				(island_removal_mode 0)
			)
			(polygon
				(pts
					(xy 7.4168 -81.4578) (xy 7.4168 -81.6102) (xy 6.8072 -81.6102) (xy 6.8072 -81.4578)
				)
			)
		)
	)
	(footprint ""
		(layer "F.Cu")
		(at 30.34538 -16.72844 180)
		(property "Reference" "R345"
			(at 0.889 5.16763 0)
			(unlocked yes)
			(layer "F.SilkS")
			(effects
				(font
					(size 0.7874 0.5842)
					(thickness 0.1524)
				)
			)
		)
		(property "Value" "VAL*"
			(at 0.02032 2.13233 180)
			(unlocked yes)
			(layer "F.Fab")
			(hide yes)
			(effects
				(font
					(size 0.7874 0.5842)
					(thickness 0.1524)
				)
			)
		)
		(property "Tolerance" "TOL*"
			(at 0.044704 3.05435 180)
			(unlocked yes)
			(layer "Cmts.User")
			(hide yes)
			(effects
				(font
					(size 0.7874 0.5842)
					(thickness 0.1524)
				)
			)
		)
		(property "User Part Number" "PARTNUM*"
			(at 0.02032 4.024884 180)
			(unlocked yes)
			(layer "Cmts.User")
			(hide yes)
			(effects
				(font
					(size 0.7874 0.5842)
					(thickness 0.1524)
				)
			)
		)
		(property "Device Type" "RESISTOR-G155-133R0-01,33OHM,1%"
			(at 0.008382 1.210564 180)
			(unlocked yes)
			(layer "F.Fab")
			(hide yes)
			(effects
				(font
					(size 0.7874 0.5842)
					(thickness 0.1524)
				)
			)
		)
		(duplicate_pad_numbers_are_jumpers no)
		(fp_line
			(start 1.143 0.5588)
			(end 1.143 -0.5588)
			(stroke
				(width 0.1)
				(type default)
			)
			(layer "F.SilkS")
		)
		(fp_line
			(start 1.143 -0.5588)
			(end -1.143 -0.5588)
			(stroke
				(width 0.1)
				(type default)
			)
			(layer "F.SilkS")
		)
		(fp_line
			(start -1.143 0.5588)
			(end 1.143 0.5588)
			(stroke
				(width 0.1)
				(type default)
			)
			(layer "F.SilkS")
		)
		(fp_line
			(start -1.143 -0.5588)
			(end -1.143 0.5588)
			(stroke
				(width 0.1)
				(type default)
			)
			(layer "F.SilkS")
		)
		(fp_rect
			(start 1.143 -0.5588)
			(end -1.143 0.5588)
			(stroke
				(width 0)
				(type default)
			)
			(fill no)
			(layer "F.CrtYd")
		)
		(fp_line
			(start 0.508 0.3048)
			(end 0.508 -0.3048)
			(stroke
				(width 0.1)
				(type default)
			)
			(layer "F.Fab")
		)
		(fp_line
			(start 0.508 -0.3048)
			(end -0.508 -0.3048)
			(stroke
				(width 0.1)
				(type default)
			)
			(layer "F.Fab")
		)
		(fp_line
			(start -0.508 0.3048)
			(end 0.508 0.3048)
			(stroke
				(width 0.1)
				(type default)
			)
			(layer "F.Fab")
		)
		(fp_line
			(start -0.508 -0.3048)
			(end -0.508 0.3048)
			(stroke
				(width 0.1)
				(type default)
			)
			(layer "F.Fab")
		)
		(pad "1" smd rect
			(at -0.5334 0 180)
			(size 0.7112 0.6096)
			(layers "F.Cu" "F.Mask" "F.Paste")
			(net "EEPROM_SDA")
		)
		(pad "2" smd rect
			(at 0.5334 0 180)
			(size 0.7112 0.6096)
			(layers "F.Cu" "F.Mask" "F.Paste")
			(net "PRI_EEPROM_SDA")
		)
		(zone
			(layer "F.Cu")
			(hatch none 0.5)
			(connect_pads
				(clearance 0)
			)
			(min_thickness 0.25)
			(keepout
				(tracks allowed)
				(vias not_allowed)
				(pads allowed)
				(copperpour not_allowed)
				(footprints allowed)
			)
			(placement
				(enabled no)
				(sheetname "")
			)
			(fill
				(thermal_gap 0.5)
				(thermal_bridge_width 0.5)
				(island_removal_mode 0)
			)
			(polygon
				(pts
					(xy 30.26918 -16.42364) (xy 30.42158 -16.42364) (xy 30.42158 -17.03324) (xy 30.26918 -17.03324)
				)
			)
		)
	)
	(footprint ""
		(layer "F.Cu")
		(at 95.123 -106.299)
		(property "Reference" "TP38"
			(at 0.8382 -0.08763 0)
			(unlocked yes)
			(layer "F.SilkS")
			(effects
				(font
					(size 0.7874 0.5842)
					(thickness 0.1524)
				)
				(justify left)
			)
		)
		(property "Value" ""
			(at 0 0 0)
			(layer "F.Fab")
			(effects
				(font
					(size 1.27 1.27)
				)
			)
		)
		(property "Device Type" "TP_PIONT-TP010CT020B030_PTH-TPA"
			(at -1.341882 0.996696 0)
			(unlocked yes)
			(layer "F.Fab")
			(hide yes)
			(effects
				(font
					(size 0.7874 0.5842)
					(thickness 0.000001)
				)
				(justify left)
			)
		)
		(duplicate_pad_numbers_are_jumpers no)
		(fp_poly
			(pts
				(arc
					(start 0.889 0)
					(mid -0.889 0)
					(end 0.889 0)
				)
			)
			(stroke
				(width 0)
				(type default)
			)
			(fill no)
			(layer "B.CrtYd")
		)
		(fp_poly
			(pts
				(arc
					(start 0.889 0)
					(mid -0.889 0)
					(end 0.889 0)
				)
			)
			(stroke
				(width 0)
				(type default)
			)
			(fill no)
			(layer "F.CrtYd")
		)
		(pad "1" thru_hole circle
			(at 0 0)
			(size 0.508 0.508)
			(drill 0.254)
			(layers "*.Cu" "*.Mask")
			(remove_unused_layers no)
			(net "XP3R3V_PG")
			(clearance 0.1016)
			(padstack
				(mode front_inner_back)
				(layer "Inner"
					(shape circle)
					(size 0.508 0.508)
					(clearance 0.1016)
				)
				(layer "B.Cu"
					(shape circle)
					(size 0.762 0.762)
					(clearance -0.0254)
				)
			)
		)
	)
	(footprint ""
		(layer "F.Cu")
		(at 145.3134 -94.2848 180)
		(property "Reference" "C4"
			(at -0.2286 -8.85317 0)
			(unlocked yes)
			(layer "F.SilkS")
			(effects
				(font
					(size 0.7874 0.5842)
					(thickness 0.1524)
				)
			)
		)
		(property "Value" "VAL*"
			(at 0.193548 2.13614 180)
			(unlocked yes)
			(layer "F.Fab")
			(hide yes)
			(effects
				(font
					(size 0.7874 0.5842)
					(thickness 0.1524)
				)
			)
		)
		(property "Tolerance" "TOL*"
			(at 0.216154 3.1496 180)
			(unlocked yes)
			(layer "Cmts.User")
			(hide yes)
			(effects
				(font
					(size 0.7874 0.5842)
					(thickness 0.1524)
				)
			)
		)
		(property "Device Type" "CAPACITOR-G104-0F224-BK,0.22UFA"
			(at 0.184404 1.180592 180)
			(unlocked yes)
			(layer "F.Fab")
			(hide yes)
			(effects
				(font
					(size 0.7874 0.5842)
					(thickness 0.1524)
				)
			)
		)
		(property "User Part Number" "PARTNUM*"
			(at 0.216154 4.185666 180)
			(unlocked yes)
			(layer "Cmts.User")
			(hide yes)
			(effects
				(font
					(size 0.7874 0.5842)
					(thickness 0.1524)
				)
			)
		)
		(duplicate_pad_numbers_are_jumpers no)
		(fp_line
			(start 0.671322 0.4445)
			(end -0.671322 0.4445)
			(stroke
				(width 0.1)
				(type default)
			)
			(layer "F.SilkS")
		)
		(fp_line
			(start 0.671322 -0.4445)
			(end 0.671322 0.4445)
			(stroke
				(width 0.1)
				(type default)
			)
			(layer "F.SilkS")
		)
		(fp_line
			(start -0.671322 0.4445)
			(end -0.671322 -0.4445)
			(stroke
				(width 0.1)
				(type default)
			)
			(layer "F.SilkS")
		)
		(fp_line
			(start -0.671322 -0.4445)
			(end 0.671322 -0.4445)
			(stroke
				(width 0.1)
				(type default)
			)
			(layer "F.SilkS")
		)
		(fp_rect
			(start 0.671322 -0.4445)
			(end -0.671322 0.4445)
			(stroke
				(width 0)
				(type default)
			)
			(fill no)
			(layer "F.CrtYd")
		)
		(fp_line
			(start 0.31496 0.1651)
			(end 0.31496 -0.1651)
			(stroke
				(width 0.1)
				(type default)
			)
			(layer "F.Fab")
		)
		(fp_line
			(start 0.31496 -0.1651)
			(end -0.31496 -0.1651)
			(stroke
				(width 0.1)
				(type default)
			)
			(layer "F.Fab")
		)
		(fp_line
			(start -0.31496 0.1651)
			(end 0.31496 0.1651)
			(stroke
				(width 0.1)
				(type default)
			)
			(layer "F.Fab")
		)
		(fp_line
			(start -0.31496 -0.1651)
			(end -0.31496 0.1651)
			(stroke
				(width 0.1)
				(type default)
			)
			(layer "F.Fab")
		)
		(pad "1" smd rect
			(at -0.264922 0 180)
			(size 0.3048 0.381)
			(layers "F.Cu" "F.Mask" "F.Paste")
			(net "SG")
		)
		(pad "2" smd rect
			(at 0.264922 0 180)
			(size 0.3048 0.381)
			(layers "F.Cu" "F.Mask" "F.Paste")
			(net "XP12R0V_A_TIMER")
		)
		(zone
			(layer "F.Cu")
			(hatch none 0.5)
			(connect_pads
				(clearance 0)
			)
			(min_thickness 0.25)
			(keepout
				(tracks allowed)
				(vias not_allowed)
				(pads allowed)
				(copperpour not_allowed)
				(footprints allowed)
			)
			(placement
				(enabled no)
				(sheetname "")
			)
			(fill
				(thermal_gap 0.5)
				(thermal_bridge_width 0.5)
				(island_removal_mode 0)
			)
			(polygon
				(pts
					(xy 145.200878 -94.0943) (xy 145.425922 -94.0943) (xy 145.425922 -94.4753) (xy 145.200878 -94.4753)
				)
			)
		)
	)
)
